# TIMECARD (Time Appliance Project (Time Card)) — schematic netlist excerpt (pin names and nets, part order shuffled) for the footprints in the layout excerpt that follows; sources: Cadence DE-HDL packaged netlist, KiCad conversion of R4006-B0001-02_R01.brd

L9  FERRITEBEAD  26OHM 25%  pkg SMC_0603R_H030  page 29 : \1\ = XP12R0V ; \2\ = VIN_XP1R0V
R235  RESISTOR  4.7KOHM 1%  pkg SMC_0402R_H016  page 15 : \1\ = VDD3V3_OSC_200M ; \2\ = CLK_200M_OE

(kicad_pcb
	(version 20260206)
	(generator "pcbnew")
	(generator_version "10.0")
	(general
		(thickness 1.6)
		(legacy_teardrops no)
	)
	(paper "A4")
	(title_block
		(title "timecard-production-celestica-r4006 — R4006-B0001-02_R01.brd")
		(comment 1 "Time Appliance Project (Time Card) / footprints 94-95 of 1113")
	)
	(layers
		(0 "F.Cu" signal "TOP")
		(4 "In1.Cu" signal "L02_GND1")
		(6 "In2.Cu" signal "L03_SIG1")
		(8 "In3.Cu" signal "L04_GND2")
		(10 "In4.Cu" signal "L05_VCC1")
		(12 "In5.Cu" signal "L06_VCC2")
		(14 "In6.Cu" signal "L07_GND3")
		(16 "In7.Cu" signal "L08_SIG2")
		(18 "In8.Cu" signal "L09_GND4")
		(2 "B.Cu" signal "BOTTOM")
		(9 "F.Adhes" user "F.Adhesive")
		(11 "B.Adhes" user "B.Adhesive")
		(13 "F.Paste" user "Package Geometry/Pastemask Top")
		(15 "B.Paste" user "Package Geometry/Pastemask Bottom")
		(5 "F.SilkS" user "Ref Des/Silkscreen Top")
		(7 "B.SilkS" user "Ref Des/Silkscreen Bottom")
		(1 "F.Mask" user "Board Geometry/Soldermask Top")
		(3 "B.Mask" user "Board Geometry/Soldermask Bottom")
		(17 "Dwgs.User" user "User.Drawings")
		(19 "Cmts.User" user "User.Comments")
		(21 "Eco1.User" user "User.Eco1")
		(23 "Eco2.User" user "User.Eco2")
		(25 "Edge.Cuts" user "Board Geometry/Outline")
		(27 "Margin" user)
		(31 "F.CrtYd" user "Package Geometry/Place Bound Top")
		(29 "B.CrtYd" user "Package Geometry/Place Bound Bottom")
		(35 "F.Fab" user "Ref Des/Assembly Top")
		(33 "B.Fab" user "Ref Des/Assembly Bottom")
	)
	(footprint ""
		(layer "F.Cu")
		(at 106.807 -22.86 -90)
		(property "Reference" "R235"
			(at -2.667 0.34163 90)
			(unlocked yes)
			(layer "F.SilkS")
			(effects
				(font
					(size 0.7874 0.5842)
					(thickness 0.1524)
				)
			)
		)
		(property "Value" "VAL*"
			(at 0.02032 2.13233 270)
			(unlocked yes)
			(layer "F.Fab")
			(hide yes)
			(effects
				(font
					(size 0.7874 0.5842)
					(thickness 0.1524)
				)
			)
		)
		(property "Device Type" "RESISTOR-G155-14701-01,4.7KOHMA"
			(at 0.008382 1.210564 270)
			(unlocked yes)
			(layer "F.Fab")
			(hide yes)
			(effects
				(font
					(size 0.7874 0.5842)
					(thickness 0.1524)
				)
			)
		)
		(property "User Part Number" "PARTNUM*"
			(at 0.02032 4.024884 270)
			(unlocked yes)
			(layer "Cmts.User")
			(hide yes)
			(effects
				(font
					(size 0.7874 0.5842)
					(thickness 0.1524)
				)
			)
		)
		(property "Tolerance" "TOL*"
			(at 0.044704 3.05435 270)
			(unlocked yes)
			(layer "Cmts.User")
			(hide yes)
			(effects
				(font
					(size 0.7874 0.5842)
					(thickness 0.1524)
				)
			)
		)
		(duplicate_pad_numbers_are_jumpers no)
		(fp_line
			(start -1.143 0.5588)
			(end 1.143 0.5588)
			(stroke
				(width 0.1)
				(type default)
			)
			(layer "F.SilkS")
		)
		(fp_line
			(start 1.143 0.5588)
			(end 1.143 -0.5588)
			(stroke
				(width 0.1)
				(type default)
			)
			(layer "F.SilkS")
		)
		(fp_line
			(start -1.143 -0.5588)
			(end -1.143 0.5588)
			(stroke
				(width 0.1)
				(type default)
			)
			(layer "F.SilkS")
		)
		(fp_line
			(start 1.143 -0.5588)
			(end -1.143 -0.5588)
			(stroke
				(width 0.1)
				(type default)
			)
			(layer "F.SilkS")
		)
		(fp_rect
			(start -1.143 0.5588)
			(end 1.143 -0.5588)
			(stroke
				(width 0)
				(type default)
			)
			(fill no)
			(layer "F.CrtYd")
		)
		(fp_line
			(start -0.508 0.3048)
			(end 0.508 0.3048)
			(stroke
				(width 0.1)
				(type default)
			)
			(layer "F.Fab")
		)
		(fp_line
			(start 0.508 0.3048)
			(end 0.508 -0.3048)
			(stroke
				(width 0.1)
				(type default)
			)
			(layer "F.Fab")
		)
		(fp_line
			(start -0.508 -0.3048)
			(end -0.508 0.3048)
			(stroke
				(width 0.1)
				(type default)
			)
			(layer "F.Fab")
		)
		(fp_line
			(start 0.508 -0.3048)
			(end -0.508 -0.3048)
			(stroke
				(width 0.1)
				(type default)
			)
			(layer "F.Fab")
		)
		(pad "1" smd rect
			(at -0.5334 0 270)
			(size 0.7112 0.6096)
			(layers "F.Cu" "F.Mask" "F.Paste")
			(net "VDD3V3_OSC_200M")
		)
		(pad "2" smd rect
			(at 0.5334 0 270)
			(size 0.7112 0.6096)
			(layers "F.Cu" "F.Mask" "F.Paste")
			(net "CLK_200M_OE")
		)
		(zone
			(layer "F.Cu")
			(hatch none 0.5)
			(connect_pads
				(clearance 0)
			)
			(min_thickness 0.25)
			(keepout
				(tracks allowed)
				(vias not_allowed)
				(pads allowed)
				(copperpour not_allowed)
				(footprints allowed)
			)
			(placement
				(enabled no)
				(sheetname "")
			)
			(fill
				(thermal_gap 0.5)
				(thermal_bridge_width 0.5)
				(island_removal_mode 0)
			)
			(polygon
				(pts
					(xy 106.5022 -22.9362) (xy 106.5022 -22.7838) (xy 107.1118 -22.7838) (xy 107.1118 -22.9362)
				)
			)
		)
	)
	(footprint ""
		(layer "F.Cu")
		(at 137.033 -57.3024 -90)
		(property "Reference" "L9"
			(at 0.0762 2.75463 90)
			(unlocked yes)
			(layer "F.SilkS")
			(effects
				(font
					(size 0.7874 0.5842)
					(thickness 0.1524)
				)
				(justify left)
			)
		)
		(property "Value" "VAL*"
			(at -0.9398 3.70967 270)
			(unlocked yes)
			(layer "F.Fab")
			(hide yes)
			(effects
				(font
					(size 0.7874 0.5842)
					(thickness 0.1524)
				)
				(justify left)
			)
		)
		(property "Tolerance" "TOL*"
			(at -0.9906 5.00507 270)
			(unlocked yes)
			(layer "Cmts.User")
			(hide yes)
			(effects
				(font
					(size 0.7874 0.5842)
					(thickness 0.1524)
				)
				(justify left)
			)
		)
		(property "User Part Number" "PARTNUM*"
			(at -2.54 2.46507 270)
			(unlocked yes)
			(layer "Cmts.User")
			(hide yes)
			(effects
				(font
					(size 0.7874 0.5842)
					(thickness 0.1524)
				)
				(justify left)
			)
		)
		(property "Device Type" "FERRITEBEAD-G191-10101-01,26OHA"
			(at -0.9906 1.22047 270)
			(unlocked yes)
			(layer "F.Fab")
			(hide yes)
			(effects
				(font
					(size 0.7874 0.5842)
					(thickness 0.1524)
				)
				(justify left)
			)
		)
		(duplicate_pad_numbers_are_jumpers no)
		(fp_line
			(start -1.3208 0.7112)
			(end -1.3208 -0.7112)
			(stroke
				(width 0.1)
				(type default)
			)
			(layer "F.SilkS")
		)
		(fp_line
			(start 1.3208 0.7112)
			(end -1.3208 0.7112)
			(stroke
				(width 0.1)
				(type default)
			)
			(layer "F.SilkS")
		)
		(fp_line
			(start -1.3208 -0.7112)
			(end 1.3208 -0.7112)
			(stroke
				(width 0.1)
				(type default)
			)
			(layer "F.SilkS")
		)
		(fp_line
			(start 1.3208 -0.7112)
			(end 1.3208 0.7112)
			(stroke
				(width 0.1)
				(type default)
			)
			(layer "F.SilkS")
		)
		(fp_rect
			(start -1.3208 0.7112)
			(end 1.3208 -0.7112)
			(stroke
				(width 0)
				(type default)
			)
			(fill no)
			(layer "F.CrtYd")
		)
		(fp_line
			(start -0.8128 0.4572)
			(end -0.8128 -0.4572)
			(stroke
				(width 0.1)
				(type default)
			)
			(layer "F.Fab")
		)
		(fp_line
			(start 0.8128 0.4572)
			(end -0.8128 0.4572)
			(stroke
				(width 0.1)
				(type default)
			)
			(layer "F.Fab")
		)
		(fp_line
			(start -0.8128 -0.4572)
			(end 0.8128 -0.4572)
			(stroke
				(width 0.1)
				(type default)
			)
			(layer "F.Fab")
		)
		(fp_line
			(start 0.8128 -0.4572)
			(end 0.8128 0.4572)
			(stroke
				(width 0.1)
				(type default)
			)
			(layer "F.Fab")
		)
		(pad "1" smd rect
			(at -0.6858 0 270)
			(size 0.762 0.8636)
			(layers "F.Cu" "F.Mask" "F.Paste")
			(net "XP12R0V")
		)
		(pad "2" smd rect
			(at 0.6858 0 270)
			(size 0.762 0.8636)
			(layers "F.Cu" "F.Mask" "F.Paste")
			(net "VIN_XP1R0V")
		)
		(zone
			(layer "F.Cu")
			(hatch none 0.5)
			(connect_pads
				(clearance 0)
			)
			(min_thickness 0.25)
			(keepout
				(tracks allowed)
				(vias not_allowed)
				(pads allowed)
				(copperpour not_allowed)
				(footprints allowed)
			)
			(placement
				(enabled no)
				(sheetname "")
			)
			(fill
				(thermal_gap 0.5)
				(thermal_bridge_width 0.5)
				(island_removal_mode 0)
			)
			(polygon
				(pts
					(xy 136.5758 -57.4548) (xy 136.5758 -57.15) (xy 137.4902 -57.15) (xy 137.4902 -57.4548)
				)
			)
		)
		(zone
			(layer "F.Cu")
			(hatch none 0.5)
			(connect_pads
				(clearance 0)
			)
			(min_thickness 0.25)
			(keepout
				(tracks not_allowed)
				(vias allowed)
				(pads allowed)
				(copperpour not_allowed)
				(footprints allowed)
			)
			(placement
				(enabled no)
				(sheetname "")
			)
			(fill
				(thermal_gap 0.5)
				(thermal_bridge_width 0.5)
				(island_removal_mode 0)
			)
			(polygon
				(pts
					(xy 136.5758 -57.4548) (xy 136.5758 -57.15) (xy 137.4902 -57.15) (xy 137.4902 -57.4548)
				)
			)
		)
	)
)
